(kicad_pcb
	(version 20260206)
	(generator "pcbnew")
	(generator_version "10.0")
	(general
		(thickness 1.6)
		(legacy_teardrops no)
	)
	(paper "A4")
	(title_block
		(title "peb — Lightning_PEB_BRD.brd")
		(comment 1 "Lightning (Wiwynn / Facebook NVMe JBOF) / footprints 189-195 of 2563")
	)
	(layers
		(0 "F.Cu" signal "TOP")
		(4 "In1.Cu" signal "L2GND")
		(6 "In2.Cu" signal "L3")
		(8 "In3.Cu" signal "L4VCC")
		(10 "In4.Cu" signal "L5VCC")
		(12 "In5.Cu" signal "L6")
		(14 "In6.Cu" signal "L7GND")
		(2 "B.Cu" signal "BOTTOM")
		(9 "F.Adhes" user "F.Adhesive")
		(11 "B.Adhes" user "B.Adhesive")
		(13 "F.Paste" user "Package Geometry/Pastemask Top")
		(15 "B.Paste" user "Package Geometry/Pastemask Bottom")
		(5 "F.SilkS" user "Ref Des/Silkscreen Top")
		(7 "B.SilkS" user "Ref Des/Silkscreen Bottom")
		(1 "F.Mask" user "Board Geometry/Soldermask Top")
		(3 "B.Mask" user "Board Geometry/Soldermask Bottom")
		(17 "Dwgs.User" user "User.Drawings")
		(19 "Cmts.User" user "User.Comments")
		(21 "Eco1.User" user "User.Eco1")
		(23 "Eco2.User" user "User.Eco2")
		(25 "Edge.Cuts" user "Board Geometry/Outline")
		(27 "Margin" user)
		(31 "F.CrtYd" user "Package Geometry/Place Bound Top")
		(29 "B.CrtYd" user "Package Geometry/Place Bound Bottom")
		(35 "F.Fab" user "Ref Des/Assembly Top")
		(33 "B.Fab" user "Ref Des/Assembly Bottom")
	)
	(footprint ""
		(layer "F.Cu")
		(at 23.3172 -183.2356 180)
		(property "Reference" "R9026"
			(at 0 0 180)
			(layer "F.SilkS")
			(hide yes)
			(effects
				(font
					(size 1.27 1.27)
				)
			)
		)
		(property "Value" "100R2D-GP"
			(at 0.064008 -3.993896 180)
			(unlocked yes)
			(layer "F.Fab")
			(hide yes)
			(effects
				(font
					(size 1.016 1.016)
					(thickness 0.1524)
				)
			)
		)
		(property "Device Type" "R402H14"
			(at 0.064008 -5.517896 180)
			(unlocked yes)
			(layer "F.Fab")
			(hide yes)
			(effects
				(font
					(size 1.016 1.016)
					(thickness 0.1524)
				)
			)
		)
		(duplicate_pad_numbers_are_jumpers no)
		(fp_line
			(start 0.508 -0.9398)
			(end -0.508 -0.9398)
			(stroke
				(width 0.1524)
				(type default)
			)
			(layer "F.SilkS")
		)
		(fp_line
			(start -0.508 -0.9398)
			(end -0.508 0.9398)
			(stroke
				(width 0.1524)
				(type default)
			)
			(layer "F.SilkS")
		)
		(fp_rect
			(start -0.508 0.9398)
			(end 0.508 -0.9398)
			(stroke
				(width 0)
				(type default)
			)
			(fill no)
			(layer "F.CrtYd")
		)
		(fp_rect
			(start -0.508 0.9398)
			(end 0.508 -0.9398)
			(stroke
				(width 0)
				(type default)
			)
			(fill no)
			(layer "F.Fab")
		)
		(pad "1" smd custom
			(at 0 -0.4445 180)
			(size 0.1397 0.1397)
			(layers "F.Cu" "F.Mask" "F.Paste")
			(net "GND")
			(options
				(clearance outline)
				(anchor circle)
			)
			(primitives
				(gr_poly
					(pts
						(arc
							(start -0.1778 -0.2794)
							(mid -0.249642 -0.249642)
							(end -0.2794 -0.1778)
						)
						(arc
							(start -0.2794 0.1778)
							(mid -0.249642 0.249642)
							(end -0.1778 0.2794)
						)
						(arc
							(start 0.1778 0.2794)
							(mid 0.249642 0.249642)
							(end 0.2794 0.1778)
						)
						(arc
							(start 0.2794 -0.1778)
							(mid 0.249642 -0.249642)
							(end 0.1778 -0.2794)
						)
					)
					(width 0)
					(fill yes)
				)
			)
		)
		(pad "2" smd custom
			(at 0 0.4445 180)
			(size 0.1397 0.1397)
			(layers "F.Cu" "F.Mask" "F.Paste")
			(net "MB0_TEMP_E")
			(options
				(clearance outline)
				(anchor circle)
			)
			(primitives
				(gr_poly
					(pts
						(arc
							(start -0.1778 -0.2794)
							(mid -0.249642 -0.249642)
							(end -0.2794 -0.1778)
						)
						(arc
							(start -0.2794 0.1778)
							(mid -0.249642 0.249642)
							(end -0.1778 0.2794)
						)
						(arc
							(start 0.1778 0.2794)
							(mid 0.249642 0.249642)
							(end 0.2794 0.1778)
						)
						(arc
							(start 0.2794 -0.1778)
							(mid 0.249642 -0.249642)
							(end 0.1778 -0.2794)
						)
					)
					(width 0)
					(fill yes)
				)
			)
		)
	)
	(footprint ""
		(layer "F.Cu")
		(at 50.673 -186.817 180)
		(property "Reference" "R900"
			(at 0 0 180)
			(layer "F.SilkS")
			(hide yes)
			(effects
				(font
					(size 1.27 1.27)
				)
			)
		)
		(property "Value" "0R2J-2-GP"
			(at 0.064008 -3.993896 180)
			(unlocked yes)
			(layer "F.Fab")
			(hide yes)
			(effects
				(font
					(size 1.016 1.016)
					(thickness 0.1524)
				)
			)
		)
		(property "Device Type" "R402H16"
			(at 0.064008 -5.517896 180)
			(unlocked yes)
			(layer "F.Fab")
			(hide yes)
			(effects
				(font
					(size 1.016 1.016)
					(thickness 0.1524)
				)
			)
		)
		(duplicate_pad_numbers_are_jumpers no)
		(fp_line
			(start 0.508 -0.9398)
			(end -0.508 -0.9398)
			(stroke
				(width 0.1524)
				(type default)
			)
			(layer "F.SilkS")
		)
		(fp_line
			(start -0.508 -0.9398)
			(end -0.508 0.9398)
			(stroke
				(width 0.1524)
				(type default)
			)
			(layer "F.SilkS")
		)
		(fp_rect
			(start -0.508 0.9398)
			(end 0.508 -0.9398)
			(stroke
				(width 0)
				(type default)
			)
			(fill no)
			(layer "F.CrtYd")
		)
		(fp_rect
			(start -0.508 0.9398)
			(end 0.508 -0.9398)
			(stroke
				(width 0)
				(type default)
			)
			(fill no)
			(layer "F.Fab")
		)
		(pad "1" smd custom
			(at 0 -0.4445 180)
			(size 0.1397 0.1397)
			(layers "F.Cu" "F.Mask" "F.Paste")
			(net "BUF_I2C8_CLKBUF1_SDA_R")
			(options
				(clearance outline)
				(anchor circle)
			)
			(primitives
				(gr_poly
					(pts
						(arc
							(start -0.1778 -0.2794)
							(mid -0.249642 -0.249642)
							(end -0.2794 -0.1778)
						)
						(arc
							(start -0.2794 0.1778)
							(mid -0.249642 0.249642)
							(end -0.1778 0.2794)
						)
						(arc
							(start 0.1778 0.2794)
							(mid 0.249642 0.249642)
							(end 0.2794 0.1778)
						)
						(arc
							(start 0.2794 -0.1778)
							(mid 0.249642 -0.249642)
							(end 0.1778 -0.2794)
						)
					)
					(width 0)
					(fill yes)
				)
			)
		)
		(pad "2" smd custom
			(at 0 0.4445 180)
			(size 0.1397 0.1397)
			(layers "F.Cu" "F.Mask" "F.Paste")
			(net "BUF_I2C8_CLKBUF1_SDA")
			(options
				(clearance outline)
				(anchor circle)
			)
			(primitives
				(gr_poly
					(pts
						(arc
							(start -0.1778 -0.2794)
							(mid -0.249642 -0.249642)
							(end -0.2794 -0.1778)
						)
						(arc
							(start -0.2794 0.1778)
							(mid -0.249642 0.249642)
							(end -0.1778 0.2794)
						)
						(arc
							(start 0.1778 0.2794)
							(mid 0.249642 0.249642)
							(end 0.2794 0.1778)
						)
						(arc
							(start 0.2794 -0.1778)
							(mid 0.249642 -0.249642)
							(end 0.1778 -0.2794)
						)
					)
					(width 0)
					(fill yes)
				)
			)
		)
	)
	(footprint ""
		(layer "F.Cu")
		(at 36.847526 -161.70148 90)
		(property "Reference" "R232"
			(at 0 0 90)
			(layer "F.SilkS")
			(hide yes)
			(effects
				(font
					(size 1.27 1.27)
				)
			)
		)
		(property "Value" "1KR2F-3-GP"
			(at 0.064008 -3.993896 90)
			(unlocked yes)
			(layer "F.Fab")
			(hide yes)
			(effects
				(font
					(size 1.016 1.016)
					(thickness 0.1524)
				)
			)
		)
		(property "Device Type" "R402H16"
			(at 0.064008 -5.517896 90)
			(unlocked yes)
			(layer "F.Fab")
			(hide yes)
			(effects
				(font
					(size 1.016 1.016)
					(thickness 0.1524)
				)
			)
		)
		(duplicate_pad_numbers_are_jumpers no)
		(fp_line
			(start 0.508 -0.9398)
			(end -0.508 -0.9398)
			(stroke
				(width 0.1524)
				(type default)
			)
			(layer "F.SilkS")
		)
		(fp_line
			(start -0.508 -0.9398)
			(end -0.508 0.9398)
			(stroke
				(width 0.1524)
				(type default)
			)
			(layer "F.SilkS")
		)
		(fp_rect
			(start -0.508 0.9398)
			(end 0.508 -0.9398)
			(stroke
				(width 0)
				(type default)
			)
			(fill no)
			(layer "F.CrtYd")
		)
		(fp_rect
			(start -0.508 0.9398)
			(end 0.508 -0.9398)
			(stroke
				(width 0)
				(type default)
			)
			(fill no)
			(layer "F.Fab")
		)
		(pad "1" smd custom
			(at 0 -0.4445 90)
			(size 0.1397 0.1397)
			(layers "F.Cu" "F.Mask" "F.Paste")
			(net "DDR_VREF")
			(options
				(clearance outline)
				(anchor circle)
			)
			(primitives
				(gr_poly
					(pts
						(arc
							(start -0.1778 -0.2794)
							(mid -0.249642 -0.249642)
							(end -0.2794 -0.1778)
						)
						(arc
							(start -0.2794 0.1778)
							(mid -0.249642 0.249642)
							(end -0.1778 0.2794)
						)
						(arc
							(start 0.1778 0.2794)
							(mid 0.249642 0.249642)
							(end 0.2794 0.1778)
						)
						(arc
							(start 0.2794 -0.1778)
							(mid 0.249642 -0.249642)
							(end 0.1778 -0.2794)
						)
					)
					(width 0)
					(fill yes)
				)
			)
		)
		(pad "2" smd custom
			(at 0 0.4445 90)
			(size 0.1397 0.1397)
			(layers "F.Cu" "F.Mask" "F.Paste")
			(net "GND")
			(options
				(clearance outline)
				(anchor circle)
			)
			(primitives
				(gr_poly
					(pts
						(arc
							(start -0.1778 -0.2794)
							(mid -0.249642 -0.249642)
							(end -0.2794 -0.1778)
						)
						(arc
							(start -0.2794 0.1778)
							(mid -0.249642 0.249642)
							(end -0.1778 0.2794)
						)
						(arc
							(start 0.1778 0.2794)
							(mid 0.249642 0.249642)
							(end 0.2794 0.1778)
						)
						(arc
							(start 0.2794 -0.1778)
							(mid 0.249642 -0.249642)
							(end 0.1778 -0.2794)
						)
					)
					(width 0)
					(fill yes)
				)
			)
		)
	)
	(footprint ""
		(layer "F.Cu")
		(at 40.259 -205.359 90)
		(property "Reference" "R876"
			(at 0 0 90)
			(layer "F.SilkS")
			(hide yes)
			(effects
				(font
					(size 1.27 1.27)
				)
			)
		)
		(property "Value" "4K7R2J-2-GP"
			(at 0.064008 -3.993896 90)
			(unlocked yes)
			(layer "F.Fab")
			(hide yes)
			(effects
				(font
					(size 1.016 1.016)
					(thickness 0.1524)
				)
			)
		)
		(property "Device Type" "R402H16"
			(at 0.064008 -5.517896 90)
			(unlocked yes)
			(layer "F.Fab")
			(hide yes)
			(effects
				(font
					(size 1.016 1.016)
					(thickness 0.1524)
				)
			)
		)
		(duplicate_pad_numbers_are_jumpers no)
		(fp_line
			(start 0.508 -0.9398)
			(end -0.508 -0.9398)
			(stroke
				(width 0.1524)
				(type default)
			)
			(layer "F.SilkS")
		)
		(fp_line
			(start -0.508 -0.9398)
			(end -0.508 0.9398)
			(stroke
				(width 0.1524)
				(type default)
			)
			(layer "F.SilkS")
		)
		(fp_rect
			(start -0.508 0.9398)
			(end 0.508 -0.9398)
			(stroke
				(width 0)
				(type default)
			)
			(fill no)
			(layer "F.CrtYd")
		)
		(fp_rect
			(start -0.508 0.9398)
			(end 0.508 -0.9398)
			(stroke
				(width 0)
				(type default)
			)
			(fill no)
			(layer "F.Fab")
		)
		(pad "1" smd custom
			(at 0 -0.4445 90)
			(size 0.1397 0.1397)
			(layers "F.Cu" "F.Mask" "F.Paste")
			(net "P3V3_STBY")
			(options
				(clearance outline)
				(anchor circle)
			)
			(primitives
				(gr_poly
					(pts
						(arc
							(start -0.1778 -0.2794)
							(mid -0.249642 -0.249642)
							(end -0.2794 -0.1778)
						)
						(arc
							(start -0.2794 0.1778)
							(mid -0.249642 0.249642)
							(end -0.1778 0.2794)
						)
						(arc
							(start 0.1778 0.2794)
							(mid 0.249642 0.249642)
							(end 0.2794 0.1778)
						)
						(arc
							(start 0.2794 -0.1778)
							(mid 0.249642 -0.249642)
							(end 0.1778 -0.2794)
						)
					)
					(width 0)
					(fill yes)
				)
			)
		)
		(pad "2" smd custom
			(at 0 0.4445 90)
			(size 0.1397 0.1397)
			(layers "F.Cu" "F.Mask" "F.Paste")
			(net "BUF_I2C6_C_FCB_SDA_R")
			(options
				(clearance outline)
				(anchor circle)
			)
			(primitives
				(gr_poly
					(pts
						(arc
							(start -0.1778 -0.2794)
							(mid -0.249642 -0.249642)
							(end -0.2794 -0.1778)
						)
						(arc
							(start -0.2794 0.1778)
							(mid -0.249642 0.249642)
							(end -0.1778 0.2794)
						)
						(arc
							(start 0.1778 0.2794)
							(mid 0.249642 0.249642)
							(end 0.2794 0.1778)
						)
						(arc
							(start 0.2794 -0.1778)
							(mid 0.249642 -0.249642)
							(end 0.1778 -0.2794)
						)
					)
					(width 0)
					(fill yes)
				)
			)
		)
	)
	(footprint ""
		(layer "F.Cu")
		(at 31.9786 -181.4322 90)
		(property "Reference" "C244"
			(at 0 0 90)
			(layer "F.SilkS")
			(hide yes)
			(effects
				(font
					(size 1.27 1.27)
				)
			)
		)
		(property "Value" "SCD01U50V2KX-1GP"
			(at 1.1811 -2.7051 90)
			(unlocked yes)
			(layer "F.Fab")
			(hide yes)
			(effects
				(font
					(size 1.016 1.016)
					(thickness 0.1524)
				)
			)
		)
		(property "Device Type" "C402H22"
			(at 1.1811 -4.2291 90)
			(unlocked yes)
			(layer "F.Fab")
			(hide yes)
			(effects
				(font
					(size 1.016 1.016)
					(thickness 0.1524)
				)
			)
		)
		(duplicate_pad_numbers_are_jumpers no)
		(fp_rect
			(start -0.4318 0.9525)
			(end 0.4318 -0.9525)
			(stroke
				(width 0)
				(type default)
			)
			(fill no)
			(layer "F.CrtYd")
		)
		(fp_rect
			(start -0.4318 0.9525)
			(end 0.4318 -0.9525)
			(stroke
				(width 0)
				(type default)
			)
			(fill no)
			(layer "F.Fab")
		)
		(pad "1" smd custom
			(at 0 -0.4445 90)
			(size 0.1524 0.1524)
			(layers "F.Cu" "F.Mask" "F.Paste")
			(net "P3V3_STBY")
			(options
				(clearance outline)
				(anchor circle)
			)
			(primitives
				(gr_poly
					(pts
						(arc
							(start 0.3048 -0.2032)
							(mid 0.275042 -0.275042)
							(end 0.2032 -0.3048)
						)
						(arc
							(start -0.2032 -0.3048)
							(mid -0.275042 -0.275042)
							(end -0.3048 -0.2032)
						)
						(arc
							(start -0.3048 0.2032)
							(mid -0.275042 0.275042)
							(end -0.2032 0.3048)
						)
						(arc
							(start 0.2032 0.3048)
							(mid 0.275042 0.275042)
							(end 0.3048 0.2032)
						)
					)
					(width 0)
					(fill yes)
				)
			)
		)
		(pad "2" smd custom
			(at 0 0.4445 90)
			(size 0.1524 0.1524)
			(layers "F.Cu" "F.Mask" "F.Paste")
			(net "GND")
			(options
				(clearance outline)
				(anchor circle)
			)
			(primitives
				(gr_poly
					(pts
						(arc
							(start 0.3048 -0.2032)
							(mid 0.275042 -0.275042)
							(end 0.2032 -0.3048)
						)
						(arc
							(start -0.2032 -0.3048)
							(mid -0.275042 -0.275042)
							(end -0.3048 -0.2032)
						)
						(arc
							(start -0.3048 0.2032)
							(mid -0.275042 0.275042)
							(end -0.2032 0.3048)
						)
						(arc
							(start 0.2032 0.3048)
							(mid 0.275042 0.275042)
							(end 0.3048 0.2032)
						)
					)
					(width 0)
					(fill yes)
				)
			)
		)
	)
	(footprint ""
		(layer "F.Cu")
		(at 16.4846 -196.5706 180)
		(property "Reference" "C7277"
			(at 0 0 180)
			(layer "F.SilkS")
			(hide yes)
			(effects
				(font
					(size 1.27 1.27)
				)
			)
		)
		(property "Value" "SC1U16V3KX-5GP"
			(at 0 -2.8194 180)
			(unlocked yes)
			(layer "F.Fab")
			(hide yes)
			(effects
				(font
					(size 1.016 1.016)
					(thickness 0.1524)
				)
			)
		)
		(property "Device Type" "C603H36"
			(at 0 -4.3434 180)
			(unlocked yes)
			(layer "F.Fab")
			(hide yes)
			(effects
				(font
					(size 1.016 1.016)
					(thickness 0.1524)
				)
			)
		)
		(duplicate_pad_numbers_are_jumpers no)
		(fp_line
			(start 0.508 0)
			(end -0.508 0)
			(stroke
				(width 0.2032)
				(type default)
			)
			(layer "F.SilkS")
		)
		(fp_rect
			(start -0.5842 1.3335)
			(end 0.5842 -1.3335)
			(stroke
				(width 0)
				(type default)
			)
			(fill no)
			(layer "F.CrtYd")
		)
		(fp_rect
			(start -0.5842 1.3335)
			(end 0.5842 -1.3335)
			(stroke
				(width 0)
				(type default)
			)
			(fill no)
			(layer "F.Fab")
		)
		(pad "1" smd custom
			(at 0 -0.762 180)
			(size 0.2159 0.2159)
			(layers "F.Cu" "F.Mask" "F.Paste")
			(net "MB0_VCAP_R")
			(options
				(clearance outline)
				(anchor circle)
			)
			(primitives
				(gr_poly
					(pts
						(arc
							(start -0.3302 -0.4318)
							(mid -0.402042 -0.402042)
							(end -0.4318 -0.3302)
						)
						(arc
							(start -0.4318 0.3302)
							(mid -0.402042 0.402042)
							(end -0.3302 0.4318)
						)
						(arc
							(start 0.3302 0.4318)
							(mid 0.402042 0.402042)
							(end 0.4318 0.3302)
						)
						(arc
							(start 0.4318 -0.3302)
							(mid 0.402042 -0.402042)
							(end 0.3302 -0.4318)
						)
					)
					(width 0)
					(fill yes)
				)
			)
		)
		(pad "2" smd custom
			(at 0 0.762 180)
			(size 0.2159 0.2159)
			(layers "F.Cu" "F.Mask" "F.Paste")
			(net "AGND_CURRENT_MON")
			(options
				(clearance outline)
				(anchor circle)
			)
			(primitives
				(gr_poly
					(pts
						(arc
							(start -0.3302 -0.4318)
							(mid -0.402042 -0.402042)
							(end -0.4318 -0.3302)
						)
						(arc
							(start -0.4318 0.3302)
							(mid -0.402042 0.402042)
							(end -0.3302 0.4318)
						)
						(arc
							(start 0.3302 0.4318)
							(mid 0.402042 0.402042)
							(end 0.4318 0.3302)
						)
						(arc
							(start 0.4318 -0.3302)
							(mid 0.402042 -0.402042)
							(end 0.3302 -0.4318)
						)
					)
					(width 0)
					(fill yes)
				)
			)
		)
	)
	(footprint ""
		(layer "F.Cu")
		(at 56.7182 -40.7924 -90)
		(property "Reference" "R628"
			(at 0 0 270)
			(layer "F.SilkS")
			(hide yes)
			(effects
				(font
					(size 1.27 1.27)
				)
			)
		)
		(property "Value" "56R6J-GP"
			(at -0.0508 -4.8514 270)
			(unlocked yes)
			(layer "F.Fab")
			(hide yes)
			(effects
				(font
					(size 1.016 1.016)
					(thickness 0.1524)
				)
			)
		)
		(property "Device Type" "R1206H26"
			(at 0 -6.3754 270)
			(unlocked yes)
			(layer "F.Fab")
			(hide yes)
			(effects
				(font
					(size 1.016 1.016)
					(thickness 0.1524)
				)
			)
		)
		(duplicate_pad_numbers_are_jumpers no)
		(fp_line
			(start -1.016 2.2352)
			(end -1.016 -2.2352)
			(stroke
				(width 0.1524)
				(type default)
			)
			(layer "F.SilkS")
		)
		(fp_line
			(start 1.016 2.2352)
			(end -1.016 2.2352)
			(stroke
				(width 0.1524)
				(type default)
			)
			(layer "F.SilkS")
		)
		(fp_line
			(start -1.016 -2.2352)
			(end 1.016 -2.2352)
			(stroke
				(width 0.1524)
				(type default)
			)
			(layer "F.SilkS")
		)
		(fp_line
			(start 1.016 -2.2352)
			(end 1.016 2.2352)
			(stroke
				(width 0.1524)
				(type default)
			)
			(layer "F.SilkS")
		)
		(fp_rect
			(start -1.0922 2.3114)
			(end 1.0922 -2.3114)
			(stroke
				(width 0)
				(type default)
			)
			(fill no)
			(layer "F.CrtYd")
		)
		(fp_poly
			(pts
				(xy -1.0922 -2.3114) (xy 1.0922 -2.3114) (xy 1.0922 2.3114) (xy -1.0922 2.3114)
			)
			(stroke
				(width 0)
				(type default)
			)
			(fill no)
			(layer "F.Fab")
		)
		(pad "1" smd rect
			(at 0 -1.397 270)
			(size 1.651 1.27)
			(layers "F.Cu" "F.Mask" "F.Paste")
			(net "P3V3_STBY")
		)
		(pad "2" smd rect
			(at 0 1.397 270)
			(size 1.651 1.27)
			(layers "F.Cu" "F.Mask" "F.Paste")
			(net "Q43_C")
		)
	)
)
